# T6G (Grand Teton) — schematic netlist excerpt (pin names and nets, part order shuffled) for the footprints in the layout excerpt that follows; sources: Cadence DE-HDL packaged netlist, KiCad conversion of 04192023_DAF0TMB3IC0_F0TG_MB_C_brd_V02_OCP.brd

R123  Q_RES  0 5% CHIP  pkg 0402LF  page 207 : A = PVDD11_S3_P0_EN ; B = PVDD11_S3_P0_EN_R
C1527  Q_CAP_DIFFBUS  DIFF BUS_0.22UF 6.3V 20% X6S  pkg C0201  page 67 : \1\ = P5E_CPU1_P3_TX_C_DP<10> ; \2\ = P5E_CPU1_P3_TX_DP<10>
R975  Q_RES  4.7K 5% EMPTY  pkg 0201LF  page 276 : A = P1V8_CPU0_RT_1D ; B = JTAG_TEST_MODE_RT_CPU0_P0

(kicad_pcb
	(version 20260206)
	(generator "pcbnew")
	(generator_version "10.0")
	(general
		(thickness 1.6)
		(legacy_teardrops no)
	)
	(paper "A4")
	(title_block
		(title "04192023_DAF0TMB3IC0_F0TG_MB_C_brd_V02_OCP.brd")
		(comment 1 "Grand Teton / footprints 1878-1880 of 8354")
	)
	(layers
		(0 "F.Cu" signal "TOP")
		(4 "In1.Cu" signal "GND")
		(6 "In2.Cu" signal "IN1")
		(8 "In3.Cu" signal "GND1")
		(10 "In4.Cu" signal "IN2")
		(12 "In5.Cu" signal "GND2")
		(14 "In6.Cu" signal "IN3")
		(16 "In7.Cu" signal "GND3")
		(18 "In8.Cu" signal "VCC")
		(20 "In9.Cu" signal "VCC1")
		(22 "In10.Cu" signal "GND4")
		(24 "In11.Cu" signal "IN4")
		(26 "In12.Cu" signal "GND5")
		(28 "In13.Cu" signal "IN5")
		(30 "In14.Cu" signal "GND6")
		(32 "In15.Cu" signal "IN6")
		(34 "In16.Cu" signal "GND7")
		(2 "B.Cu" signal "BOTTOM")
		(9 "F.Adhes" user "F.Adhesive")
		(11 "B.Adhes" user "B.Adhesive")
		(13 "F.Paste" user "Package Geometry/Pastemask Top")
		(15 "B.Paste" user "Package Geometry/Pastemask Bottom")
		(5 "F.SilkS" user "Ref Des/Silkscreen Top")
		(7 "B.SilkS" user "Ref Des/Silkscreen Bottom")
		(1 "F.Mask" user "Board Geometry/Soldermask Top")
		(3 "B.Mask" user "Board Geometry/Soldermask Bottom")
		(17 "Dwgs.User" user "User.Drawings")
		(19 "Cmts.User" user "User.Comments")
		(21 "Eco1.User" user "User.Eco1")
		(23 "Eco2.User" user "User.Eco2")
		(25 "Edge.Cuts" user "Board Geometry/Outline")
		(27 "Margin" user)
		(31 "F.CrtYd" user "Package Geometry/Place Bound Top")
		(29 "B.CrtYd" user "Package Geometry/Place Bound Bottom")
		(35 "F.Fab" user "Ref Des/Assembly Top")
		(33 "B.Fab" user "Ref Des/Assembly Bottom")
	)
	(footprint ""
		(layer "F.Cu")
		(at 296.385742 -400.1516 -90)
		(property "Reference" "R975"
			(at 0 0 270)
			(layer "F.SilkS")
			(hide yes)
			(effects
				(font
					(size 1.27 1.27)
				)
			)
		)
		(property "Value" ""
			(at 0 0 270)
			(layer "F.Fab")
			(effects
				(font
					(size 1.27 1.27)
				)
			)
		)
		(duplicate_pad_numbers_are_jumpers no)
		(fp_line
			(start -0.32512 0.175006)
			(end -0.32512 -0.175006)
			(stroke
				(width 0.1)
				(type default)
			)
			(layer "F.Fab")
		)
		(fp_line
			(start 0.32512 0.175006)
			(end -0.32512 0.175006)
			(stroke
				(width 0.1)
				(type default)
			)
			(layer "F.Fab")
		)
		(fp_line
			(start -0.32512 -0.175006)
			(end 0.32512 -0.175006)
			(stroke
				(width 0.1)
				(type default)
			)
			(layer "F.Fab")
		)
		(fp_line
			(start 0.32512 -0.175006)
			(end 0.32512 0.175006)
			(stroke
				(width 0.1)
				(type default)
			)
			(layer "F.Fab")
		)
		(pad "1" smd rect
			(at -0.2667 0 270)
			(size 0.3048 0.381)
			(layers "F.Cu" "F.Mask" "F.Paste")
			(net "P1V8_CPU0_RT_1D")
		)
		(pad "2" smd rect
			(at 0.2667 0 90)
			(size 0.3048 0.381)
			(layers "F.Cu" "F.Mask" "F.Paste")
			(net "JTAG_TEST_MODE_RT_CPU0_P0")
		)
	)
	(footprint ""
		(layer "F.Cu")
		(at 128.809496 -375.49963 -90)
		(property "Reference" "C1527"
			(at 0 0 270)
			(layer "F.SilkS")
			(hide yes)
			(effects
				(font
					(size 1.27 1.27)
				)
			)
		)
		(property "Value" ""
			(at 0 0 270)
			(layer "F.Fab")
			(effects
				(font
					(size 1.27 1.27)
				)
			)
		)
		(duplicate_pad_numbers_are_jumpers no)
		(fp_line
			(start -0.299974 0.150114)
			(end -0.299974 -0.150114)
			(stroke
				(width 0.1)
				(type default)
			)
			(layer "F.Fab")
		)
		(fp_line
			(start 0.299974 0.150114)
			(end -0.299974 0.150114)
			(stroke
				(width 0.1)
				(type default)
			)
			(layer "F.Fab")
		)
		(fp_line
			(start -0.299974 -0.150114)
			(end 0.299974 -0.150114)
			(stroke
				(width 0.1)
				(type default)
			)
			(layer "F.Fab")
		)
		(fp_line
			(start 0.299974 -0.150114)
			(end 0.299974 0.150114)
			(stroke
				(width 0.1)
				(type default)
			)
			(layer "F.Fab")
		)
		(pad "1" smd rect
			(at -0.2667 0 270)
			(size 0.3048 0.381)
			(layers "F.Cu" "F.Mask" "F.Paste")
			(net "P5E_CPU1_P3_TX_C_DP<10>")
		)
		(pad "2" smd rect
			(at 0.2667 0 270)
			(size 0.3048 0.381)
			(layers "F.Cu" "F.Mask" "F.Paste")
			(net "P5E_CPU1_P3_TX_DP<10>")
		)
	)
	(footprint ""
		(layer "F.Cu")
		(at 411.734 -364.236 -90)
		(property "Reference" "R123"
			(at 0 0 270)
			(layer "F.SilkS")
			(hide yes)
			(effects
				(font
					(size 1.27 1.27)
				)
			)
		)
		(property "Value" ""
			(at 0 0 270)
			(layer "F.Fab")
			(effects
				(font
					(size 1.27 1.27)
				)
			)
		)
		(duplicate_pad_numbers_are_jumpers no)
		(fp_line
			(start -0.7874 0.4064)
			(end -0.7874 -0.4064)
			(stroke
				(width 0.1524)
				(type default)
			)
			(layer "F.SilkS")
		)
		(fp_line
			(start 0.7874 0.4064)
			(end -0.7874 0.4064)
			(stroke
				(width 0.1524)
				(type default)
			)
			(layer "F.SilkS")
		)
		(fp_line
			(start -0.7874 -0.4064)
			(end 0.7874 -0.4064)
			(stroke
				(width 0.1524)
				(type default)
			)
			(layer "F.SilkS")
		)
		(fp_line
			(start 0.7874 -0.4064)
			(end 0.7874 0.4064)
			(stroke
				(width 0.1524)
				(type default)
			)
			(layer "F.SilkS")
		)
		(fp_line
			(start -0.67945 0.3048)
			(end -0.67945 -0.305054)
			(stroke
				(width 0.1)
				(type default)
			)
			(layer "F.Fab")
		)
		(fp_line
			(start -0.12065 0.3048)
			(end -0.67945 0.3048)
			(stroke
				(width 0.1)
				(type default)
			)
			(layer "F.Fab")
		)
		(fp_line
			(start 0.120396 0.3048)
			(end 0.120396 0.2794)
			(stroke
				(width 0.1)
				(type default)
			)
			(layer "F.Fab")
		)
		(fp_line
			(start 0.67945 0.3048)
			(end 0.120396 0.3048)
			(stroke
				(width 0.1)
				(type default)
			)
			(layer "F.Fab")
		)
		(fp_line
			(start -0.12065 0.2794)
			(end -0.12065 0.3048)
			(stroke
				(width 0.1)
				(type default)
			)
			(layer "F.Fab")
		)
		(fp_line
			(start 0.120396 0.2794)
			(end -0.12065 0.2794)
			(stroke
				(width 0.1)
				(type default)
			)
			(layer "F.Fab")
		)
		(fp_line
			(start -0.12065 -0.2794)
			(end 0.12065 -0.2794)
			(stroke
				(width 0.1)
				(type default)
			)
			(layer "F.Fab")
		)
		(fp_line
			(start 0.12065 -0.2794)
			(end 0.12065 -0.3048)
			(stroke
				(width 0.1)
				(type default)
			)
			(layer "F.Fab")
		)
		(fp_line
			(start 0.12065 -0.3048)
			(end 0.67945 -0.3048)
			(stroke
				(width 0.1)
				(type default)
			)
			(layer "F.Fab")
		)
		(fp_line
			(start 0.67945 -0.3048)
			(end 0.67945 0.3048)
			(stroke
				(width 0.1)
				(type default)
			)
			(layer "F.Fab")
		)
		(fp_line
			(start -0.67945 -0.305054)
			(end -0.12065 -0.305054)
			(stroke
				(width 0.1)
				(type default)
			)
			(layer "F.Fab")
		)
		(fp_line
			(start -0.12065 -0.305054)
			(end -0.12065 -0.2794)
			(stroke
				(width 0.1)
				(type default)
			)
			(layer "F.Fab")
		)
		(pad "1" smd circle
			(at -0.40005 0 270)
			(size 0 0)
			(layers "F.Cu" "F.Mask" "F.Paste")
			(net "PVDD11_S3_P0_EN")
		)
		(pad "2" smd circle
			(at 0.40005 0 270)
			(size 0 0)
			(layers "F.Cu" "F.Mask" "F.Paste")
			(net "PVDD11_S3_P0_EN_R")
		)
	)
)
